# BASEBOARD_FAB2 (Tioga Pass) — schematic netlist excerpt (pin names and nets, part order shuffled) for the footprints in the layout excerpt that follows; sources: Cadence DE-HDL packaged netlist, KiCad conversion of Wiwynn_Tioga_Pass_MB.brd

C5D12  CAP  10UF 4V 20% X6S  pkg 0603LF  page 42 : A = PVSA_CPU0 ; B = GND
R3D4  RES  49.9 1% CHIP  pkg 0402  page 55 : A = A_CPU1_MCP01_RBIAS ; B = GND
R4E5  RES  1.00K 1% CHIP  pkg 0402  page 201 : A = P3V3_STBY ; B = PWRGD_PVSA_CPU0_R

(kicad_pcb
	(version 20260206)
	(generator "pcbnew")
	(generator_version "10.0")
	(general
		(thickness 1.6)
		(legacy_teardrops no)
	)
	(paper "A4")
	(title_block
		(title "Wiwynn_Tioga_Pass_MB.brd")
		(comment 1 "Tioga Pass / footprints 1133-1135 of 4770")
	)
	(layers
		(0 "F.Cu" signal "TOP")
		(4 "In1.Cu" signal "L2GND")
		(6 "In2.Cu" signal "L3")
		(8 "In3.Cu" signal "L4GND")
		(10 "In4.Cu" signal "L5")
		(12 "In5.Cu" signal "L6GND")
		(14 "In6.Cu" signal "L7VCC")
		(16 "In7.Cu" signal "L8VCC")
		(18 "In8.Cu" signal "L9GND")
		(20 "In9.Cu" signal "L10")
		(22 "In10.Cu" signal "L11GND")
		(24 "In11.Cu" signal "L12")
		(26 "In12.Cu" signal "L13GND")
		(2 "B.Cu" signal "BOTTOM")
		(9 "F.Adhes" user "F.Adhesive")
		(11 "B.Adhes" user "B.Adhesive")
		(13 "F.Paste" user "Package Geometry/Pastemask Top")
		(15 "B.Paste" user "Package Geometry/Pastemask Bottom")
		(5 "F.SilkS" user "Ref Des/Silkscreen Top")
		(7 "B.SilkS" user "Ref Des/Silkscreen Bottom")
		(1 "F.Mask" user "Board Geometry/Soldermask Top")
		(3 "B.Mask" user "Board Geometry/Soldermask Bottom")
		(17 "Dwgs.User" user "User.Drawings")
		(19 "Cmts.User" user "User.Comments")
		(21 "Eco1.User" user "User.Eco1")
		(23 "Eco2.User" user "User.Eco2")
		(25 "Edge.Cuts" user "Board Geometry/Outline")
		(27 "Margin" user)
		(31 "F.CrtYd" user "Package Geometry/Place Bound Top")
		(29 "B.CrtYd" user "Package Geometry/Place Bound Bottom")
		(35 "F.Fab" user "Ref Des/Assembly Top")
		(33 "B.Fab" user "Ref Des/Assembly Bottom")
	)
	(footprint ""
		(layer "F.Cu")
		(at 181.356 -64.135 180)
		(property "Reference" "R4E5"
			(at 0 0 180)
			(layer "F.SilkS")
			(hide yes)
			(effects
				(font
					(size 1.27 1.27)
				)
			)
		)
		(property "Value" ""
			(at 0 0 180)
			(layer "F.Fab")
			(effects
				(font
					(size 1.27 1.27)
				)
			)
		)
		(duplicate_pad_numbers_are_jumpers no)
		(fp_rect
			(start 0.2794 -0.1016)
			(end -0.2794 0.9906)
			(stroke
				(width 0)
				(type default)
			)
			(fill no)
			(layer "F.CrtYd")
		)
		(fp_line
			(start 0.2794 0.9906)
			(end 0.2794 -0.1016)
			(stroke
				(width 0.1)
				(type default)
			)
			(layer "F.Fab")
		)
		(fp_line
			(start 0.2794 -0.1016)
			(end -0.2794 -0.1016)
			(stroke
				(width 0.1)
				(type default)
			)
			(layer "F.Fab")
		)
		(fp_line
			(start -0.2794 0.9906)
			(end 0.2794 0.9906)
			(stroke
				(width 0.1)
				(type default)
			)
			(layer "F.Fab")
		)
		(fp_line
			(start -0.2794 -0.1016)
			(end -0.2794 0.9906)
			(stroke
				(width 0.1)
				(type default)
			)
			(layer "F.Fab")
		)
		(pad "1" smd rect
			(at 0 0 180)
			(size 0.508 0.508)
			(layers "F.Cu" "F.Mask" "F.Paste")
			(net "P3V3_STBY")
		)
		(pad "2" smd rect
			(at 0 0.889 180)
			(size 0.508 0.508)
			(layers "F.Cu" "F.Mask" "F.Paste")
			(net "PWRGD_PVSA_CPU0_R")
		)
		(zone
			(layer "F.Cu")
			(hatch none 0.5)
			(connect_pads
				(clearance 0)
			)
			(min_thickness 0.25)
			(keepout
				(tracks not_allowed)
				(vias allowed)
				(pads allowed)
				(copperpour not_allowed)
				(footprints allowed)
			)
			(placement
				(enabled no)
				(sheetname "")
			)
			(fill
				(thermal_gap 0.5)
				(thermal_bridge_width 0.5)
				(island_removal_mode 0)
			)
			(polygon
				(pts
					(xy 181.102 -64.389) (xy 181.61 -64.389) (xy 181.61 -64.77) (xy 181.102 -64.77)
				)
			)
		)
		(zone
			(layer "F.Cu")
			(hatch none 0.5)
			(connect_pads
				(clearance 0)
			)
			(min_thickness 0.25)
			(keepout
				(tracks allowed)
				(vias not_allowed)
				(pads allowed)
				(copperpour not_allowed)
				(footprints allowed)
			)
			(placement
				(enabled no)
				(sheetname "")
			)
			(fill
				(thermal_gap 0.5)
				(thermal_bridge_width 0.5)
				(island_removal_mode 0)
			)
			(polygon
				(pts
					(xy 181.102 -64.389) (xy 181.61 -64.389) (xy 181.61 -64.77) (xy 181.102 -64.77)
				)
			)
		)
	)
	(footprint ""
		(layer "F.Cu")
		(at 112.2934 -83.8962)
		(property "Reference" "R3D4"
			(at 0 0 0)
			(layer "F.SilkS")
			(hide yes)
			(effects
				(font
					(size 1.27 1.27)
				)
			)
		)
		(property "Value" ""
			(at 0 0 0)
			(layer "F.Fab")
			(effects
				(font
					(size 1.27 1.27)
				)
			)
		)
		(duplicate_pad_numbers_are_jumpers no)
		(fp_poly
			(pts
				(xy -0.2794 -0.1016) (xy 0.2794 -0.1016) (xy 0.2794 0.9906) (xy -0.2794 0.9906)
			)
			(stroke
				(width 0)
				(type default)
			)
			(fill no)
			(layer "F.CrtYd")
		)
		(fp_line
			(start -0.2794 -0.1016)
			(end -0.2794 0.9906)
			(stroke
				(width 0.1)
				(type default)
			)
			(layer "F.Fab")
		)
		(fp_line
			(start -0.2794 0.9906)
			(end 0.2794 0.9906)
			(stroke
				(width 0.1)
				(type default)
			)
			(layer "F.Fab")
		)
		(fp_line
			(start 0.2794 -0.1016)
			(end -0.2794 -0.1016)
			(stroke
				(width 0.1)
				(type default)
			)
			(layer "F.Fab")
		)
		(fp_line
			(start 0.2794 0.9906)
			(end 0.2794 -0.1016)
			(stroke
				(width 0.1)
				(type default)
			)
			(layer "F.Fab")
		)
		(pad "1" smd rect
			(at 0 0)
			(size 0.508 0.508)
			(layers "F.Cu" "F.Mask" "F.Paste")
			(net "A_CPU1_MCP01_RBIAS")
		)
		(pad "2" smd rect
			(at 0 0.889)
			(size 0.508 0.508)
			(layers "F.Cu" "F.Mask" "F.Paste")
			(net "GND")
		)
		(zone
			(layer "F.Cu")
			(hatch none 0.5)
			(connect_pads
				(clearance 0)
			)
			(min_thickness 0.25)
			(keepout
				(tracks allowed)
				(vias not_allowed)
				(pads allowed)
				(copperpour not_allowed)
				(footprints allowed)
			)
			(placement
				(enabled no)
				(sheetname "")
			)
			(fill
				(thermal_gap 0.5)
				(thermal_bridge_width 0.5)
				(island_removal_mode 0)
			)
			(polygon
				(pts
					(xy 112.0394 -83.6422) (xy 112.5474 -83.6422) (xy 112.5474 -83.2612) (xy 112.0394 -83.2612)
				)
			)
		)
		(zone
			(layer "F.Cu")
			(hatch none 0.5)
			(connect_pads
				(clearance 0)
			)
			(min_thickness 0.25)
			(keepout
				(tracks not_allowed)
				(vias allowed)
				(pads allowed)
				(copperpour not_allowed)
				(footprints allowed)
			)
			(placement
				(enabled no)
				(sheetname "")
			)
			(fill
				(thermal_gap 0.5)
				(thermal_bridge_width 0.5)
				(island_removal_mode 0)
			)
			(polygon
				(pts
					(xy 112.0394 -83.2612) (xy 112.5474 -83.2612) (xy 112.5474 -83.6422) (xy 112.0394 -83.6422)
				)
			)
		)
	)
	(footprint ""
		(layer "F.Cu")
		(at 260.697472 -81.573116)
		(property "Reference" "C5D12"
			(at 0 0 0)
			(layer "F.SilkS")
			(hide yes)
			(effects
				(font
					(size 1.27 1.27)
				)
			)
		)
		(property "Value" ""
			(at 0 0 0)
			(layer "F.Fab")
			(effects
				(font
					(size 1.27 1.27)
				)
			)
		)
		(duplicate_pad_numbers_are_jumpers no)
		(fp_poly
			(pts
				(xy -0.4953 -0.2032) (xy 0.4953 -0.2032) (xy 0.4953 1.6002) (xy -0.4953 1.6002)
			)
			(stroke
				(width 0)
				(type default)
			)
			(fill no)
			(layer "F.CrtYd")
		)
		(fp_line
			(start -0.4953 -0.2032)
			(end 0.4953 -0.2032)
			(stroke
				(width 0.1)
				(type default)
			)
			(layer "F.Fab")
		)
		(fp_line
			(start -0.4953 1.6002)
			(end -0.4953 -0.2032)
			(stroke
				(width 0.1)
				(type default)
			)
			(layer "F.Fab")
		)
		(fp_line
			(start 0.4953 -0.2032)
			(end 0.4953 1.6002)
			(stroke
				(width 0.1)
				(type default)
			)
			(layer "F.Fab")
		)
		(fp_line
			(start 0.4953 1.6002)
			(end -0.4953 1.6002)
			(stroke
				(width 0.1)
				(type default)
			)
			(layer "F.Fab")
		)
		(pad "1" smd rect
			(at 0 0)
			(size 0.762 0.889)
			(layers "F.Cu" "F.Mask" "F.Paste")
			(net "PVSA_CPU0")
		)
		(pad "2" smd rect
			(at 0 1.397)
			(size 0.762 0.889)
			(layers "F.Cu" "F.Mask" "F.Paste")
			(net "GND")
		)
		(zone
			(layer "F.Cu")
			(hatch none 0.5)
			(connect_pads
				(clearance 0)
			)
			(min_thickness 0.25)
			(keepout
				(tracks not_allowed)
				(vias allowed)
				(pads allowed)
				(copperpour not_allowed)
				(footprints allowed)
			)
			(placement
				(enabled no)
				(sheetname "")
			)
			(fill
				(thermal_gap 0.5)
				(thermal_bridge_width 0.5)
				(island_removal_mode 0)
			)
			(polygon
				(pts
					(xy 260.316472 -81.128616) (xy 261.078472 -81.128616) (xy 261.078472 -80.620616) (xy 260.316472 -80.620616)
				)
			)
		)
	)
)
